(kicad_pcb
	(version 20260206)
	(generator "pcbnew")
	(generator_version "10.0")
	(general
		(thickness 1.6)
		(legacy_teardrops no)
	)
	(paper "A4")
	(title_block
		(title "4HDD Backplane_Layout.brd")
		(comment 1 "Tioga Pass / footprints 72-77 of 97")
	)
	(layers
		(0 "F.Cu" signal "TOP")
		(4 "In1.Cu" signal "L2GND")
		(6 "In2.Cu" signal "L3")
		(8 "In3.Cu" signal "L4")
		(10 "In4.Cu" signal "L5GND")
		(2 "B.Cu" signal "BOTTOM")
		(9 "F.Adhes" user "F.Adhesive")
		(11 "B.Adhes" user "B.Adhesive")
		(13 "F.Paste" user "Package Geometry/Pastemask Top")
		(15 "B.Paste" user "Package Geometry/Pastemask Bottom")
		(5 "F.SilkS" user "Ref Des/Silkscreen Top")
		(7 "B.SilkS" user "Ref Des/Silkscreen Bottom")
		(1 "F.Mask" user "Board Geometry/Soldermask Top")
		(3 "B.Mask" user "Board Geometry/Soldermask Bottom")
		(17 "Dwgs.User" user "User.Drawings")
		(19 "Cmts.User" user "User.Comments")
		(21 "Eco1.User" user "User.Eco1")
		(23 "Eco2.User" user "User.Eco2")
		(25 "Edge.Cuts" user "Board Geometry/Outline")
		(27 "Margin" user)
		(31 "F.CrtYd" user "Package Geometry/Place Bound Top")
		(29 "B.CrtYd" user "Package Geometry/Place Bound Bottom")
		(35 "F.Fab" user "Ref Des/Assembly Top")
		(33 "B.Fab" user "Ref Des/Assembly Bottom")
	)
	(footprint ""
		(layer "B.Cu")
		(at 73.794366 -14.873478 90)
		(property "Reference" "PR1"
			(at 0 0 90)
			(layer "B.SilkS")
			(hide yes)
			(effects
				(font
					(size 1.27 1.27)
				)
				(justify mirror)
			)
		)
		(property "Value" "1K2R3F-GP"
			(at 0.0254 -2.5146 90)
			(unlocked yes)
			(layer "B.Fab")
			(hide yes)
			(effects
				(font
					(size 1.016 1.016)
					(thickness 0.1524)
				)
				(justify mirror)
			)
		)
		(property "Device Type" "R603H22"
			(at 0.0254 -4.0386 90)
			(unlocked yes)
			(layer "B.Fab")
			(hide yes)
			(effects
				(font
					(size 1.016 1.016)
					(thickness 0.1524)
				)
				(justify mirror)
			)
		)
		(duplicate_pad_numbers_are_jumpers no)
		(fp_line
			(start 0.4826 0)
			(end 0.2032 0)
			(stroke
				(width 0.2032)
				(type default)
			)
			(layer "B.SilkS")
		)
		(fp_line
			(start -0.2032 0)
			(end -0.4826 0)
			(stroke
				(width 0.2032)
				(type default)
			)
			(layer "B.SilkS")
		)
		(fp_rect
			(start 0.5842 1.3335)
			(end -0.5842 -1.3335)
			(stroke
				(width 0)
				(type default)
			)
			(fill no)
			(layer "B.CrtYd")
		)
		(fp_rect
			(start 0.5842 1.3335)
			(end -0.5842 -1.3335)
			(stroke
				(width 0)
				(type default)
			)
			(fill no)
			(layer "B.Fab")
		)
		(pad "1" smd custom
			(at 0 -0.762 270)
			(size 0.2159 0.2159)
			(layers "B.Cu" "B.Mask" "B.Paste")
			(net "P5V")
			(options
				(clearance outline)
				(anchor circle)
			)
			(primitives
				(gr_poly
					(pts
						(arc
							(start -0.3302 0.4318)
							(mid -0.402042 0.402042)
							(end -0.4318 0.3302)
						)
						(arc
							(start -0.4318 -0.3302)
							(mid -0.402042 -0.402042)
							(end -0.3302 -0.4318)
						)
						(arc
							(start 0.3302 -0.4318)
							(mid 0.402042 -0.402042)
							(end 0.4318 -0.3302)
						)
						(arc
							(start 0.4318 0.3302)
							(mid 0.402042 0.402042)
							(end 0.3302 0.4318)
						)
					)
					(width 0)
					(fill yes)
				)
			)
		)
		(pad "2" smd custom
			(at 0 0.762 270)
			(size 0.2159 0.2159)
			(layers "B.Cu" "B.Mask" "B.Paste")
			(net "P5V_R_E1")
			(options
				(clearance outline)
				(anchor circle)
			)
			(primitives
				(gr_poly
					(pts
						(arc
							(start -0.3302 0.4318)
							(mid -0.402042 0.402042)
							(end -0.4318 0.3302)
						)
						(arc
							(start -0.4318 -0.3302)
							(mid -0.402042 -0.402042)
							(end -0.3302 -0.4318)
						)
						(arc
							(start 0.3302 -0.4318)
							(mid 0.402042 -0.402042)
							(end 0.4318 -0.3302)
						)
						(arc
							(start 0.4318 0.3302)
							(mid 0.402042 0.402042)
							(end 0.3302 0.4318)
						)
					)
					(width 0)
					(fill yes)
				)
			)
		)
	)
	(footprint ""
		(layer "B.Cu")
		(at 84.328 -45.212)
		(property "Reference" "R164"
			(at 0 0 0)
			(layer "B.SilkS")
			(hide yes)
			(effects
				(font
					(size 1.27 1.27)
				)
				(justify mirror)
			)
		)
		(property "Value" "4K7R2J-2-GP"
			(at -0.064008 -3.993896 0)
			(unlocked yes)
			(layer "B.Fab")
			(hide yes)
			(effects
				(font
					(size 1.016 1.016)
					(thickness 0.1524)
				)
				(justify mirror)
			)
		)
		(property "Device Type" "R402H16"
			(at -0.064008 -5.517896 0)
			(unlocked yes)
			(layer "B.Fab")
			(hide yes)
			(effects
				(font
					(size 1.016 1.016)
					(thickness 0.1524)
				)
				(justify mirror)
			)
		)
		(duplicate_pad_numbers_are_jumpers no)
		(fp_line
			(start -0.508 -0.9398)
			(end 0.508 -0.9398)
			(stroke
				(width 0.1524)
				(type default)
			)
			(layer "B.SilkS")
		)
		(fp_line
			(start 0.508 -0.9398)
			(end 0.508 0.9398)
			(stroke
				(width 0.1524)
				(type default)
			)
			(layer "B.SilkS")
		)
		(fp_rect
			(start 0.508 0.9398)
			(end -0.508 -0.9398)
			(stroke
				(width 0)
				(type default)
			)
			(fill no)
			(layer "B.CrtYd")
		)
		(fp_rect
			(start 0.508 0.9398)
			(end -0.508 -0.9398)
			(stroke
				(width 0)
				(type default)
			)
			(fill no)
			(layer "B.Fab")
		)
		(pad "1" smd custom
			(at 0 -0.4445 180)
			(size 0.1397 0.1397)
			(layers "B.Cu" "B.Mask" "B.Paste")
			(net "P12V")
			(options
				(clearance outline)
				(anchor circle)
			)
			(primitives
				(gr_poly
					(pts
						(arc
							(start -0.1778 0.2794)
							(mid -0.249642 0.249642)
							(end -0.2794 0.1778)
						)
						(arc
							(start -0.2794 -0.1778)
							(mid -0.249642 -0.249642)
							(end -0.1778 -0.2794)
						)
						(arc
							(start 0.1778 -0.2794)
							(mid 0.249642 -0.249642)
							(end 0.2794 -0.1778)
						)
						(arc
							(start 0.2794 0.1778)
							(mid 0.249642 0.249642)
							(end 0.1778 0.2794)
						)
					)
					(width 0)
					(fill yes)
				)
			)
		)
		(pad "2" smd custom
			(at 0 0.4445 180)
			(size 0.1397 0.1397)
			(layers "B.Cu" "B.Mask" "B.Paste")
			(net "PWR_EN_R_P5V")
			(options
				(clearance outline)
				(anchor circle)
			)
			(primitives
				(gr_poly
					(pts
						(arc
							(start -0.1778 0.2794)
							(mid -0.249642 0.249642)
							(end -0.2794 0.1778)
						)
						(arc
							(start -0.2794 -0.1778)
							(mid -0.249642 -0.249642)
							(end -0.1778 -0.2794)
						)
						(arc
							(start 0.1778 -0.2794)
							(mid 0.249642 -0.249642)
							(end 0.2794 -0.1778)
						)
						(arc
							(start 0.2794 0.1778)
							(mid 0.249642 0.249642)
							(end 0.1778 0.2794)
						)
					)
					(width 0)
					(fill yes)
				)
			)
		)
	)
	(footprint ""
		(layer "B.Cu")
		(at 90.0176 -7.4676 90)
		(property "Reference" "D3"
			(at 0 0 90)
			(layer "B.SilkS")
			(hide yes)
			(effects
				(font
					(size 1.27 1.27)
				)
				(justify mirror)
			)
		)
		(property "Value" "LRB551V-30T1G-GP"
			(at 0 -6.7818 90)
			(unlocked yes)
			(layer "B.Fab")
			(hide yes)
			(effects
				(font
					(size 1.016 1.016)
					(thickness 0.1524)
				)
				(justify mirror)
			)
		)
		(property "Device Type" "SOD323AKH44"
			(at 0 -8.6868 90)
			(unlocked yes)
			(layer "B.Fab")
			(hide yes)
			(effects
				(font
					(size 1.016 1.016)
					(thickness 0.1524)
				)
				(justify mirror)
			)
		)
		(duplicate_pad_numbers_are_jumpers no)
		(fp_line
			(start 0.889 -1.9304)
			(end -0.889 -1.9304)
			(stroke
				(width 0.1524)
				(type default)
			)
			(layer "B.SilkS")
		)
		(fp_line
			(start -0.889 -1.9304)
			(end -0.889 2.159)
			(stroke
				(width 0.1524)
				(type default)
			)
			(layer "B.SilkS")
		)
		(fp_line
			(start -0.762 2.0574)
			(end 0.762 2.0574)
			(stroke
				(width 0.508)
				(type default)
			)
			(layer "B.SilkS")
		)
		(fp_line
			(start 0.889 2.159)
			(end 0.889 -1.9304)
			(stroke
				(width 0.1524)
				(type default)
			)
			(layer "B.SilkS")
		)
		(fp_line
			(start -0.889 2.159)
			(end 0.889 2.159)
			(stroke
				(width 0.1524)
				(type default)
			)
			(layer "B.SilkS")
		)
		(fp_rect
			(start 1.016 2.3114)
			(end -1.016 -2.0066)
			(stroke
				(width 0)
				(type default)
			)
			(fill no)
			(layer "B.CrtYd")
		)
		(fp_poly
			(pts
				(xy 1.016 -2.0066) (xy -1.016 -2.0066) (xy -1.016 2.3114) (xy 1.016 2.3114)
			)
			(stroke
				(width 0)
				(type default)
			)
			(fill no)
			(layer "B.Fab")
		)
		(pad "A" smd rect
			(at 0 -1.143 270)
			(size 0.5588 1.016)
			(layers "B.Cu" "B.Mask" "B.Paste")
			(net "SW_SW_L_0")
		)
		(pad "K" smd rect
			(at 0 1.143 270)
			(size 0.5588 1.016)
			(layers "B.Cu" "B.Mask" "B.Paste")
			(net "SW_SW_L_N_0")
		)
	)
	(footprint ""
		(layer "B.Cu")
		(at 75.0062 -38.1 -90)
		(property "Reference" "C11"
			(at 0 0 90)
			(layer "B.SilkS")
			(hide yes)
			(effects
				(font
					(size 1.27 1.27)
				)
				(justify mirror)
			)
		)
		(property "Value" "SC10U25V6KX-1GP"
			(at 0.0762 -5.1308 270)
			(unlocked yes)
			(layer "B.Fab")
			(hide yes)
			(effects
				(font
					(size 1.016 1.016)
					(thickness 0.1524)
				)
				(justify mirror)
			)
		)
		(property "Device Type" "C1206H71"
			(at 0.127 -6.6548 270)
			(unlocked yes)
			(layer "B.Fab")
			(hide yes)
			(effects
				(font
					(size 1.016 1.016)
					(thickness 0.1524)
				)
				(justify mirror)
			)
		)
		(duplicate_pad_numbers_are_jumpers no)
		(fp_line
			(start -1.016 2.2352)
			(end 1.016 2.2352)
			(stroke
				(width 0.1524)
				(type default)
			)
			(layer "B.SilkS")
		)
		(fp_line
			(start 1.016 2.2352)
			(end 1.016 0.8382)
			(stroke
				(width 0.1524)
				(type default)
			)
			(layer "B.SilkS")
		)
		(fp_line
			(start -1.016 0.8382)
			(end -1.016 2.2352)
			(stroke
				(width 0.1524)
				(type default)
			)
			(layer "B.SilkS")
		)
		(fp_line
			(start 1.016 -0.8382)
			(end 1.016 -2.2352)
			(stroke
				(width 0.1524)
				(type default)
			)
			(layer "B.SilkS")
		)
		(fp_line
			(start -1.016 -2.2352)
			(end -1.016 -0.8382)
			(stroke
				(width 0.1524)
				(type default)
			)
			(layer "B.SilkS")
		)
		(fp_line
			(start 1.016 -2.2352)
			(end -1.016 -2.2352)
			(stroke
				(width 0.1524)
				(type default)
			)
			(layer "B.SilkS")
		)
		(fp_rect
			(start 1.0922 2.3114)
			(end -1.0922 -2.3114)
			(stroke
				(width 0)
				(type default)
			)
			(fill no)
			(layer "B.CrtYd")
		)
		(fp_poly
			(pts
				(xy -1.0922 -2.3114) (xy -1.0922 2.3114) (xy 1.0922 2.3114) (xy 1.0922 -2.3114)
			)
			(stroke
				(width 0)
				(type default)
			)
			(fill no)
			(layer "B.Fab")
		)
		(pad "1" smd rect
			(at 0 -1.397 90)
			(size 1.651 1.27)
			(layers "B.Cu" "B.Mask" "B.Paste")
			(net "P12V_SW_R")
		)
		(pad "2" smd rect
			(at 0 1.397 90)
			(size 1.651 1.27)
			(layers "B.Cu" "B.Mask" "B.Paste")
			(net "GND")
		)
	)
	(footprint ""
		(layer "B.Cu")
		(at 81.059274 -49.797716 90)
		(property "Reference" "Q1"
			(at 0 0 90)
			(layer "B.SilkS")
			(hide yes)
			(effects
				(font
					(size 1.27 1.27)
				)
				(justify mirror)
			)
		)
		(property "Value" "FDS8878-G-GP"
			(at 3.707384 -1.5367 90)
			(unlocked yes)
			(layer "B.Fab")
			(hide yes)
			(effects
				(font
					(size 1.016 1.016)
					(thickness 0.1524)
				)
				(justify mirror)
			)
		)
		(property "Device Type" "SOIC8H69"
			(at 3.707384 -3.0607 90)
			(unlocked yes)
			(layer "B.Fab")
			(hide yes)
			(effects
				(font
					(size 1.016 1.016)
					(thickness 0.1524)
				)
				(justify mirror)
			)
		)
		(duplicate_pad_numbers_are_jumpers no)
		(fp_line
			(start 2.7432 -1.4224)
			(end 2.7432 1.4224)
			(stroke
				(width 0.1524)
				(type default)
			)
			(layer "B.SilkS")
		)
		(fp_line
			(start -2.1336 -1.4224)
			(end 2.7432 -1.4224)
			(stroke
				(width 0.1524)
				(type default)
			)
			(layer "B.SilkS")
		)
		(fp_line
			(start 2.7178 -0.508)
			(end 2.1844 -0.0508)
			(stroke
				(width 0.1524)
				(type default)
			)
			(layer "B.SilkS")
		)
		(fp_line
			(start 2.1844 -0.0508)
			(end 2.7178 0.508)
			(stroke
				(width 0.1524)
				(type default)
			)
			(layer "B.SilkS")
		)
		(fp_line
			(start 2.7432 1.4224)
			(end 2.6416 1.4224)
			(stroke
				(width 0.1524)
				(type default)
			)
			(layer "B.SilkS")
		)
		(fp_line
			(start 2.7432 1.4224)
			(end -2.1336 1.4224)
			(stroke
				(width 0.1524)
				(type default)
			)
			(layer "B.SilkS")
		)
		(fp_line
			(start -2.1336 1.4224)
			(end -2.1336 -1.4224)
			(stroke
				(width 0.1524)
				(type default)
			)
			(layer "B.SilkS")
		)
		(fp_line
			(start 2.6289 3.4417)
			(end 2.6289 1.4732)
			(stroke
				(width 0.381)
				(type default)
			)
			(layer "B.SilkS")
		)
		(fp_poly
			(pts
				(xy 2.2098 -1.4224) (xy 2.2098 1.4224) (xy -2.2098 1.4224) (xy -2.2098 -1.4224)
			)
			(stroke
				(width 0)
				(type default)
			)
			(fill yes)
			(layer "B.SilkS")
		)
		(fp_rect
			(start 2.450084 2.999994)
			(end -2.450084 -2.999994)
			(stroke
				(width 0)
				(type default)
			)
			(fill no)
			(layer "B.CrtYd")
		)
		(fp_poly
			(pts
				(xy 2.8194 3.6322) (xy 2.8194 -3.6322) (xy -2.8194 -3.6322) (xy -2.8194 1.18364) (xy -2.450084 1.18364)
				(xy -2.450084 -2.999994) (xy 2.450084 -2.999994) (xy 2.450084 2.999994) (xy -2.450084 2.999994)
				(xy -2.450084 1.18618) (xy -2.8194 1.18618) (xy -2.8194 3.6322)
			)
			(stroke
				(width 0)
				(type default)
			)
			(fill no)
			(layer "B.CrtYd")
		)
		(fp_rect
			(start 2.8194 3.6322)
			(end -2.8194 -3.6322)
			(stroke
				(width 0)
				(type default)
			)
			(fill no)
			(layer "B.Fab")
		)
		(pad "1" smd rect
			(at 1.905 2.54 270)
			(size 0.635 1.651)
			(layers "B.Cu" "B.Mask" "B.Paste")
			(net "P5V")
		)
		(pad "2" smd rect
			(at 0.635 2.54 270)
			(size 0.635 1.651)
			(layers "B.Cu" "B.Mask" "B.Paste")
			(net "P5V")
		)
		(pad "3" smd rect
			(at -0.635 2.54 270)
			(size 0.635 1.651)
			(layers "B.Cu" "B.Mask" "B.Paste")
			(net "P5V")
		)
		(pad "4" smd rect
			(at -1.905 2.54 270)
			(size 0.635 1.651)
			(layers "B.Cu" "B.Mask" "B.Paste")
			(net "PWR_EN_R_P5V")
		)
		(pad "5" smd rect
			(at -1.905 -2.54 270)
			(size 0.635 1.651)
			(layers "B.Cu" "B.Mask" "B.Paste")
			(net "P5V_SW_R")
		)
		(pad "6" smd rect
			(at -0.635 -2.54 270)
			(size 0.635 1.651)
			(layers "B.Cu" "B.Mask" "B.Paste")
			(net "P5V_SW_R")
		)
		(pad "7" smd rect
			(at 0.635 -2.54 270)
			(size 0.635 1.651)
			(layers "B.Cu" "B.Mask" "B.Paste")
			(net "P5V_SW_R")
		)
		(pad "8" smd rect
			(at 1.905 -2.54 270)
			(size 0.635 1.651)
			(layers "B.Cu" "B.Mask" "B.Paste")
			(net "P5V_SW_R")
		)
	)
	(footprint ""
		(layer "B.Cu")
		(at 83.320636 -45.220636 180)
		(property "Reference" "C516"
			(at 0 0 0)
			(layer "B.SilkS")
			(hide yes)
			(effects
				(font
					(size 1.27 1.27)
				)
				(justify mirror)
			)
		)
		(property "Value" "SCD033U25V2KX-GP"
			(at -1.1811 -2.7051 180)
			(unlocked yes)
			(layer "B.Fab")
			(hide yes)
			(effects
				(font
					(size 1.016 1.016)
					(thickness 0.1524)
				)
				(justify mirror)
			)
		)
		(property "Device Type" "C402H22"
			(at -1.1811 -4.2291 180)
			(unlocked yes)
			(layer "B.Fab")
			(hide yes)
			(effects
				(font
					(size 1.016 1.016)
					(thickness 0.1524)
				)
				(justify mirror)
			)
		)
		(duplicate_pad_numbers_are_jumpers no)
		(fp_rect
			(start 0.4318 0.9525)
			(end -0.4318 -0.9525)
			(stroke
				(width 0)
				(type default)
			)
			(fill no)
			(layer "B.CrtYd")
		)
		(fp_rect
			(start 0.4318 0.9525)
			(end -0.4318 -0.9525)
			(stroke
				(width 0)
				(type default)
			)
			(fill no)
			(layer "B.Fab")
		)
		(pad "1" smd custom
			(at 0 -0.4445)
			(size 0.1524 0.1524)
			(layers "B.Cu" "B.Mask" "B.Paste")
			(net "PWR_EN_R_P5V")
			(options
				(clearance outline)
				(anchor circle)
			)
			(primitives
				(gr_poly
					(pts
						(arc
							(start 0.3048 0.2032)
							(mid 0.275042 0.275042)
							(end 0.2032 0.3048)
						)
						(arc
							(start -0.2032 0.3048)
							(mid -0.275042 0.275042)
							(end -0.3048 0.2032)
						)
						(arc
							(start -0.3048 -0.2032)
							(mid -0.275042 -0.275042)
							(end -0.2032 -0.3048)
						)
						(arc
							(start 0.2032 -0.3048)
							(mid 0.275042 -0.275042)
							(end 0.3048 -0.2032)
						)
					)
					(width 0)
					(fill yes)
				)
			)
		)
		(pad "2" smd custom
			(at 0 0.4445)
			(size 0.1524 0.1524)
			(layers "B.Cu" "B.Mask" "B.Paste")
			(net "GND")
			(options
				(clearance outline)
				(anchor circle)
			)
			(primitives
				(gr_poly
					(pts
						(arc
							(start 0.3048 0.2032)
							(mid 0.275042 0.275042)
							(end 0.2032 0.3048)
						)
						(arc
							(start -0.2032 0.3048)
							(mid -0.275042 0.275042)
							(end -0.3048 0.2032)
						)
						(arc
							(start -0.3048 -0.2032)
							(mid -0.275042 -0.275042)
							(end -0.2032 -0.3048)
						)
						(arc
							(start 0.2032 -0.3048)
							(mid 0.275042 -0.275042)
							(end 0.3048 -0.2032)
						)
					)
					(width 0)
					(fill yes)
				)
			)
		)
	)
)
